# SCM (Grand Teton) — schematic netlist excerpt (pin names and nets, part order shuffled) for the footprints in the layout excerpt that follows; sources: Cadence DE-HDL packaged netlist, KiCad conversion of 12092022_DA0F0TMDCD0_F0T_Management_Board_D_brd_V3_OCP.brd

R538  Q_RES  100K 1% CHIP  pkg 0402LF  page 31 : A = P3V3_AUX ; B = UART_6_BMC_RXD_R
PC261  Q_CAP  10UF 25V 10% X6S  pkg C0805  page 56 : A = SW_P1V0_AUX_FLT ; B = GND
C201  Q_CAP  0.1UF 25V 10% X7R  pkg 0402  page 50 : A = P3V3_AUX ; B = GND

(kicad_pcb
	(version 20260206)
	(generator "pcbnew")
	(generator_version "10.0")
	(general
		(thickness 1.6)
		(legacy_teardrops no)
	)
	(paper "A4")
	(title_block
		(title "12092022_DA0F0TMDCD0_F0T_Management_Board_D_brd_V3_OCP.brd")
		(comment 1 "Grand Teton / footprints 313-315 of 1440")
	)
	(layers
		(0 "F.Cu" signal "TOP")
		(4 "In1.Cu" signal "GND")
		(6 "In2.Cu" signal "IN1")
		(8 "In3.Cu" signal "GND1")
		(10 "In4.Cu" signal "IN2")
		(12 "In5.Cu" signal "VCC")
		(14 "In6.Cu" signal "VCC1")
		(16 "In7.Cu" signal "IN3")
		(18 "In8.Cu" signal "GND2")
		(20 "In9.Cu" signal "IN4")
		(22 "In10.Cu" signal "GND3")
		(2 "B.Cu" signal "BOTTOM")
		(9 "F.Adhes" user "F.Adhesive")
		(11 "B.Adhes" user "B.Adhesive")
		(13 "F.Paste" user "Package Geometry/Pastemask Top")
		(15 "B.Paste" user "Package Geometry/Pastemask Bottom")
		(5 "F.SilkS" user "Ref Des/Silkscreen Top")
		(7 "B.SilkS" user "Ref Des/Silkscreen Bottom")
		(1 "F.Mask" user "Board Geometry/Soldermask Top")
		(3 "B.Mask" user "Board Geometry/Soldermask Bottom")
		(17 "Dwgs.User" user "User.Drawings")
		(19 "Cmts.User" user "User.Comments")
		(21 "Eco1.User" user "User.Eco1")
		(23 "Eco2.User" user "User.Eco2")
		(25 "Edge.Cuts" user "Board Geometry/Outline")
		(27 "Margin" user)
		(31 "F.CrtYd" user "Package Geometry/Place Bound Top")
		(29 "B.CrtYd" user "Package Geometry/Place Bound Bottom")
		(35 "F.Fab" user "Ref Des/Assembly Top")
		(33 "B.Fab" user "Ref Des/Assembly Bottom")
	)
	(footprint ""
		(layer "F.Cu")
		(at 80.6704 -15.9258)
		(property "Reference" "C201"
			(at 0 0 0)
			(layer "F.SilkS")
			(hide yes)
			(effects
				(font
					(size 1.27 1.27)
				)
			)
		)
		(property "Value" ""
			(at 0 0 0)
			(layer "F.Fab")
			(effects
				(font
					(size 1.27 1.27)
				)
			)
		)
		(duplicate_pad_numbers_are_jumpers no)
		(fp_line
			(start -0.7874 -0.4064)
			(end 0.7874 -0.4064)
			(stroke
				(width 0.1524)
				(type default)
			)
			(layer "F.SilkS")
		)
		(fp_line
			(start -0.7874 0.4064)
			(end -0.7874 -0.4064)
			(stroke
				(width 0.1524)
				(type default)
			)
			(layer "F.SilkS")
		)
		(fp_line
			(start 0.7874 -0.4064)
			(end 0.7874 0.4064)
			(stroke
				(width 0.1524)
				(type default)
			)
			(layer "F.SilkS")
		)
		(fp_line
			(start 0.7874 0.4064)
			(end -0.7874 0.4064)
			(stroke
				(width 0.1524)
				(type default)
			)
			(layer "F.SilkS")
		)
		(fp_line
			(start -0.67945 -0.305054)
			(end -0.12065 -0.305054)
			(stroke
				(width 0.1)
				(type default)
			)
			(layer "F.Fab")
		)
		(fp_line
			(start -0.67945 0.3048)
			(end -0.67945 -0.305054)
			(stroke
				(width 0.1)
				(type default)
			)
			(layer "F.Fab")
		)
		(fp_line
			(start -0.12065 -0.305054)
			(end -0.12065 -0.2794)
			(stroke
				(width 0.1)
				(type default)
			)
			(layer "F.Fab")
		)
		(fp_line
			(start -0.12065 -0.2794)
			(end 0.12065 -0.2794)
			(stroke
				(width 0.1)
				(type default)
			)
			(layer "F.Fab")
		)
		(fp_line
			(start -0.12065 0.2794)
			(end -0.12065 0.3048)
			(stroke
				(width 0.1)
				(type default)
			)
			(layer "F.Fab")
		)
		(fp_line
			(start -0.12065 0.3048)
			(end -0.67945 0.3048)
			(stroke
				(width 0.1)
				(type default)
			)
			(layer "F.Fab")
		)
		(fp_line
			(start 0.120396 0.2794)
			(end -0.12065 0.2794)
			(stroke
				(width 0.1)
				(type default)
			)
			(layer "F.Fab")
		)
		(fp_line
			(start 0.120396 0.3048)
			(end 0.120396 0.2794)
			(stroke
				(width 0.1)
				(type default)
			)
			(layer "F.Fab")
		)
		(fp_line
			(start 0.12065 -0.3048)
			(end 0.67945 -0.3048)
			(stroke
				(width 0.1)
				(type default)
			)
			(layer "F.Fab")
		)
		(fp_line
			(start 0.12065 -0.2794)
			(end 0.12065 -0.3048)
			(stroke
				(width 0.1)
				(type default)
			)
			(layer "F.Fab")
		)
		(fp_line
			(start 0.67945 -0.3048)
			(end 0.67945 0.3048)
			(stroke
				(width 0.1)
				(type default)
			)
			(layer "F.Fab")
		)
		(fp_line
			(start 0.67945 0.3048)
			(end 0.120396 0.3048)
			(stroke
				(width 0.1)
				(type default)
			)
			(layer "F.Fab")
		)
		(pad "1" smd circle
			(at -0.40005 0)
			(size 0 0)
			(layers "F.Cu" "F.Mask" "F.Paste")
			(net "P3V3_AUX")
		)
		(pad "2" smd circle
			(at 0.40005 0)
			(size 0 0)
			(layers "F.Cu" "F.Mask" "F.Paste")
			(net "GND")
		)
	)
	(footprint ""
		(layer "F.Cu")
		(at 20.701 -56.1848 90)
		(property "Reference" "R538"
			(at 0 0 90)
			(layer "F.SilkS")
			(hide yes)
			(effects
				(font
					(size 1.27 1.27)
				)
			)
		)
		(property "Value" ""
			(at 0 0 90)
			(layer "F.Fab")
			(effects
				(font
					(size 1.27 1.27)
				)
			)
		)
		(duplicate_pad_numbers_are_jumpers no)
		(fp_line
			(start 0.7874 -0.4064)
			(end 0.7874 0.4064)
			(stroke
				(width 0.1524)
				(type default)
			)
			(layer "F.SilkS")
		)
		(fp_line
			(start -0.7874 -0.4064)
			(end 0.7874 -0.4064)
			(stroke
				(width 0.1524)
				(type default)
			)
			(layer "F.SilkS")
		)
		(fp_line
			(start 0.7874 0.4064)
			(end -0.7874 0.4064)
			(stroke
				(width 0.1524)
				(type default)
			)
			(layer "F.SilkS")
		)
		(fp_line
			(start -0.7874 0.4064)
			(end -0.7874 -0.4064)
			(stroke
				(width 0.1524)
				(type default)
			)
			(layer "F.SilkS")
		)
		(fp_line
			(start -0.12065 -0.305054)
			(end -0.12065 -0.2794)
			(stroke
				(width 0.1)
				(type default)
			)
			(layer "F.Fab")
		)
		(fp_line
			(start -0.67945 -0.305054)
			(end -0.12065 -0.305054)
			(stroke
				(width 0.1)
				(type default)
			)
			(layer "F.Fab")
		)
		(fp_line
			(start 0.67945 -0.3048)
			(end 0.67945 0.3048)
			(stroke
				(width 0.1)
				(type default)
			)
			(layer "F.Fab")
		)
		(fp_line
			(start 0.12065 -0.3048)
			(end 0.67945 -0.3048)
			(stroke
				(width 0.1)
				(type default)
			)
			(layer "F.Fab")
		)
		(fp_line
			(start 0.12065 -0.2794)
			(end 0.12065 -0.3048)
			(stroke
				(width 0.1)
				(type default)
			)
			(layer "F.Fab")
		)
		(fp_line
			(start -0.12065 -0.2794)
			(end 0.12065 -0.2794)
			(stroke
				(width 0.1)
				(type default)
			)
			(layer "F.Fab")
		)
		(fp_line
			(start 0.120396 0.2794)
			(end -0.12065 0.2794)
			(stroke
				(width 0.1)
				(type default)
			)
			(layer "F.Fab")
		)
		(fp_line
			(start -0.12065 0.2794)
			(end -0.12065 0.3048)
			(stroke
				(width 0.1)
				(type default)
			)
			(layer "F.Fab")
		)
		(fp_line
			(start 0.67945 0.3048)
			(end 0.120396 0.3048)
			(stroke
				(width 0.1)
				(type default)
			)
			(layer "F.Fab")
		)
		(fp_line
			(start 0.120396 0.3048)
			(end 0.120396 0.2794)
			(stroke
				(width 0.1)
				(type default)
			)
			(layer "F.Fab")
		)
		(fp_line
			(start -0.12065 0.3048)
			(end -0.67945 0.3048)
			(stroke
				(width 0.1)
				(type default)
			)
			(layer "F.Fab")
		)
		(fp_line
			(start -0.67945 0.3048)
			(end -0.67945 -0.305054)
			(stroke
				(width 0.1)
				(type default)
			)
			(layer "F.Fab")
		)
		(pad "1" smd circle
			(at -0.40005 0 90)
			(size 0 0)
			(layers "F.Cu" "F.Mask" "F.Paste")
			(net "P3V3_AUX")
		)
		(pad "2" smd circle
			(at 0.40005 0 90)
			(size 0 0)
			(layers "F.Cu" "F.Mask" "F.Paste")
			(net "UART_6_BMC_RXD_R")
		)
	)
	(footprint ""
		(layer "F.Cu")
		(at 19.3421 -35.967162 180)
		(property "Reference" "PC261"
			(at 0 0 180)
			(layer "F.SilkS")
			(hide yes)
			(effects
				(font
					(size 1.27 1.27)
				)
			)
		)
		(property "Value" ""
			(at 0 0 180)
			(layer "F.Fab")
			(effects
				(font
					(size 1.27 1.27)
				)
			)
		)
		(duplicate_pad_numbers_are_jumpers no)
		(fp_line
			(start 1.651 0.8382)
			(end -1.651 0.8382)
			(stroke
				(width 0.1524)
				(type default)
			)
			(layer "F.SilkS")
		)
		(fp_line
			(start 1.651 -0.8382)
			(end 1.651 0.8382)
			(stroke
				(width 0.1524)
				(type default)
			)
			(layer "F.SilkS")
		)
		(fp_line
			(start 0 0.8382)
			(end 0 -0.8382)
			(stroke
				(width 0.1524)
				(type default)
			)
			(layer "F.SilkS")
		)
		(fp_line
			(start -1.651 0.8382)
			(end -1.651 -0.8382)
			(stroke
				(width 0.1524)
				(type default)
			)
			(layer "F.SilkS")
		)
		(fp_line
			(start -1.651 -0.8382)
			(end 1.651 -0.8382)
			(stroke
				(width 0.1524)
				(type default)
			)
			(layer "F.SilkS")
		)
		(fp_line
			(start 1.55956 0.7366)
			(end 1.55956 -0.7366)
			(stroke
				(width 0.1)
				(type default)
			)
			(layer "F.Fab")
		)
		(fp_line
			(start 1.55956 -0.7366)
			(end 1.524 -0.7366)
			(stroke
				(width 0.1)
				(type default)
			)
			(layer "F.Fab")
		)
		(fp_line
			(start 1.524 0.7366)
			(end 1.55956 0.7366)
			(stroke
				(width 0.1)
				(type default)
			)
			(layer "F.Fab")
		)
		(fp_line
			(start 1.524 -0.7366)
			(end -1.524 -0.7366)
			(stroke
				(width 0.1)
				(type default)
			)
			(layer "F.Fab")
		)
		(fp_line
			(start -1.524 0.7366)
			(end 1.524 0.7366)
			(stroke
				(width 0.1)
				(type default)
			)
			(layer "F.Fab")
		)
		(fp_line
			(start -1.524 -0.7366)
			(end -1.55956 -0.7366)
			(stroke
				(width 0.1)
				(type default)
			)
			(layer "F.Fab")
		)
		(fp_line
			(start -1.55956 0.7366)
			(end -1.524 0.7366)
			(stroke
				(width 0.1)
				(type default)
			)
			(layer "F.Fab")
		)
		(fp_line
			(start -1.55956 -0.7366)
			(end -1.55956 0.7366)
			(stroke
				(width 0.1)
				(type default)
			)
			(layer "F.Fab")
		)
		(pad "1" smd rect
			(at -0.94996 0)
			(size 1.1176 1.3716)
			(layers "F.Cu" "F.Mask" "F.Paste")
			(net "SW_P1V0_AUX_FLT")
		)
		(pad "2" smd rect
			(at 0.94996 0)
			(size 1.1176 1.3716)
			(layers "F.Cu" "F.Mask" "F.Paste")
			(net "GND")
		)
	)
)
